(kicad_pcb
	(version 20260206)
	(generator "pcbnew")
	(generator_version "10.0")
	(general
		(thickness 1.6)
		(legacy_teardrops no)
	)
	(paper "A4")
	(title_block
		(title "Bryce Canyon_F.DPB_16315-1-OCP.brd")
		(comment 1 "Bryce Canyon / footprints 151-158 of 2223")
	)
	(layers
		(0 "F.Cu" signal "TOP")
		(4 "In1.Cu" signal "L2GND")
		(6 "In2.Cu" signal "L3")
		(8 "In3.Cu" signal "L4GND")
		(10 "In4.Cu" signal "L5")
		(12 "In5.Cu" signal "L6VCC")
		(14 "In6.Cu" signal "L7VCC")
		(16 "In7.Cu" signal "L8")
		(18 "In8.Cu" signal "L9GND")
		(20 "In9.Cu" signal "L10")
		(22 "In10.Cu" signal "L11GND")
		(2 "B.Cu" signal "BOTTOM")
		(9 "F.Adhes" user "F.Adhesive")
		(11 "B.Adhes" user "B.Adhesive")
		(13 "F.Paste" user "Package Geometry/Pastemask Top")
		(15 "B.Paste" user "Package Geometry/Pastemask Bottom")
		(5 "F.SilkS" user "Ref Des/Silkscreen Top")
		(7 "B.SilkS" user "Ref Des/Silkscreen Bottom")
		(1 "F.Mask" user "Board Geometry/Soldermask Top")
		(3 "B.Mask" user "Board Geometry/Soldermask Bottom")
		(17 "Dwgs.User" user "User.Drawings")
		(19 "Cmts.User" user "User.Comments")
		(21 "Eco1.User" user "User.Eco1")
		(23 "Eco2.User" user "User.Eco2")
		(25 "Edge.Cuts" user "Board Geometry/Outline")
		(27 "Margin" user)
		(31 "F.CrtYd" user "Package Geometry/Place Bound Top")
		(29 "B.CrtYd" user "Package Geometry/Place Bound Bottom")
		(35 "F.Fab" user "Ref Des/Assembly Top")
		(33 "B.Fab" user "Ref Des/Assembly Bottom")
	)
	(footprint ""
		(layer "F.Cu")
		(at 457.3905 -272.535142)
		(property "Reference" "R373"
			(at 0 0 0)
			(layer "F.SilkS")
			(hide yes)
			(effects
				(font
					(size 1.27 1.27)
				)
			)
		)
		(property "Value" "4K7R2J-2-GP"
			(at 0.064008 -3.993896 0)
			(unlocked yes)
			(layer "F.Fab")
			(hide yes)
			(effects
				(font
					(size 1.016 1.016)
					(thickness 0.1524)
				)
			)
		)
		(property "Device Type" "R402H16"
			(at 0.064008 -5.517896 0)
			(unlocked yes)
			(layer "F.Fab")
			(hide yes)
			(effects
				(font
					(size 1.016 1.016)
					(thickness 0.1524)
				)
			)
		)
		(duplicate_pad_numbers_are_jumpers no)
		(fp_line
			(start -0.508 -0.9398)
			(end -0.508 0.9398)
			(stroke
				(width 0.1524)
				(type default)
			)
			(layer "F.SilkS")
		)
		(fp_line
			(start 0.508 -0.9398)
			(end -0.508 -0.9398)
			(stroke
				(width 0.1524)
				(type default)
			)
			(layer "F.SilkS")
		)
		(fp_rect
			(start -0.508 0.9398)
			(end 0.508 -0.9398)
			(stroke
				(width 0)
				(type default)
			)
			(fill no)
			(layer "F.CrtYd")
		)
		(fp_rect
			(start -0.508 0.9398)
			(end 0.508 -0.9398)
			(stroke
				(width 0)
				(type default)
			)
			(fill no)
			(layer "F.Fab")
		)
		(pad "1" smd custom
			(at 0 -0.4445)
			(size 0.1397 0.1397)
			(layers "F.Cu" "F.Mask" "F.Paste")
			(net "SW_PWR_R_HDD10")
			(options
				(clearance outline)
				(anchor circle)
			)
			(primitives
				(gr_poly
					(pts
						(arc
							(start -0.1778 -0.2794)
							(mid -0.249642 -0.249642)
							(end -0.2794 -0.1778)
						)
						(arc
							(start -0.2794 0.1778)
							(mid -0.249642 0.249642)
							(end -0.1778 0.2794)
						)
						(arc
							(start 0.1778 0.2794)
							(mid 0.249642 0.249642)
							(end 0.2794 0.1778)
						)
						(arc
							(start 0.2794 -0.1778)
							(mid 0.249642 -0.249642)
							(end 0.1778 -0.2794)
						)
					)
					(width 0)
					(fill yes)
				)
			)
		)
		(pad "2" smd custom
			(at 0 0.4445)
			(size 0.1397 0.1397)
			(layers "F.Cu" "F.Mask" "F.Paste")
			(net "GND")
			(options
				(clearance outline)
				(anchor circle)
			)
			(primitives
				(gr_poly
					(pts
						(arc
							(start -0.1778 -0.2794)
							(mid -0.249642 -0.249642)
							(end -0.2794 -0.1778)
						)
						(arc
							(start -0.2794 0.1778)
							(mid -0.249642 0.249642)
							(end -0.1778 0.2794)
						)
						(arc
							(start 0.1778 0.2794)
							(mid 0.249642 0.249642)
							(end 0.2794 0.1778)
						)
						(arc
							(start 0.2794 -0.1778)
							(mid 0.249642 -0.249642)
							(end 0.1778 -0.2794)
						)
					)
					(width 0)
					(fill yes)
				)
			)
		)
	)
	(footprint ""
		(layer "F.Cu")
		(at 191.135 -290.068)
		(property "Reference" "C111"
			(at 0 0 0)
			(layer "F.SilkS")
			(hide yes)
			(effects
				(font
					(size 1.27 1.27)
				)
			)
		)
		(property "Value" "SCD01U50V2KX-1GP"
			(at 1.1811 -2.7051 0)
			(unlocked yes)
			(layer "F.Fab")
			(hide yes)
			(effects
				(font
					(size 1.016 1.016)
					(thickness 0.1524)
				)
			)
		)
		(property "Device Type" "C402H22"
			(at 1.1811 -4.2291 0)
			(unlocked yes)
			(layer "F.Fab")
			(hide yes)
			(effects
				(font
					(size 1.016 1.016)
					(thickness 0.1524)
				)
			)
		)
		(duplicate_pad_numbers_are_jumpers no)
		(fp_rect
			(start -0.4318 0.9525)
			(end 0.4318 -0.9525)
			(stroke
				(width 0)
				(type default)
			)
			(fill no)
			(layer "F.CrtYd")
		)
		(fp_rect
			(start -0.4318 0.9525)
			(end 0.4318 -0.9525)
			(stroke
				(width 0)
				(type default)
			)
			(fill no)
			(layer "F.Fab")
		)
		(pad "1" smd custom
			(at 0 -0.4445)
			(size 0.1524 0.1524)
			(layers "F.Cu" "F.Mask" "F.Paste")
			(net "HDD_PRSNT_5")
			(options
				(clearance outline)
				(anchor circle)
			)
			(primitives
				(gr_poly
					(pts
						(arc
							(start 0.3048 -0.2032)
							(mid 0.275042 -0.275042)
							(end 0.2032 -0.3048)
						)
						(arc
							(start -0.2032 -0.3048)
							(mid -0.275042 -0.275042)
							(end -0.3048 -0.2032)
						)
						(arc
							(start -0.3048 0.2032)
							(mid -0.275042 0.275042)
							(end -0.2032 0.3048)
						)
						(arc
							(start 0.2032 0.3048)
							(mid 0.275042 0.275042)
							(end 0.3048 0.2032)
						)
					)
					(width 0)
					(fill yes)
				)
			)
		)
		(pad "2" smd custom
			(at 0 0.4445)
			(size 0.1524 0.1524)
			(layers "F.Cu" "F.Mask" "F.Paste")
			(net "GND")
			(options
				(clearance outline)
				(anchor circle)
			)
			(primitives
				(gr_poly
					(pts
						(arc
							(start 0.3048 -0.2032)
							(mid 0.275042 -0.275042)
							(end 0.2032 -0.3048)
						)
						(arc
							(start -0.2032 -0.3048)
							(mid -0.275042 -0.275042)
							(end -0.3048 -0.2032)
						)
						(arc
							(start -0.3048 0.2032)
							(mid -0.275042 0.275042)
							(end -0.2032 0.3048)
						)
						(arc
							(start 0.2032 0.3048)
							(mid 0.275042 0.275042)
							(end 0.3048 0.2032)
						)
					)
					(width 0)
					(fill yes)
				)
			)
		)
	)
	(footprint ""
		(layer "F.Cu")
		(at 77.942948 -59.857894)
		(property "Reference" "Q158"
			(at 0 0 0)
			(layer "F.SilkS")
			(hide yes)
			(effects
				(font
					(size 1.27 1.27)
				)
			)
		)
		(property "Value" "AO4407AL-GP"
			(at -3.707384 -1.5367 0)
			(unlocked yes)
			(layer "F.Fab")
			(hide yes)
			(effects
				(font
					(size 1.016 1.016)
					(thickness 0.1524)
				)
			)
		)
		(property "Device Type" "SOIC8H69"
			(at -3.707384 -3.0607 0)
			(unlocked yes)
			(layer "F.Fab")
			(hide yes)
			(effects
				(font
					(size 1.016 1.016)
					(thickness 0.1524)
				)
			)
		)
		(duplicate_pad_numbers_are_jumpers no)
		(fp_line
			(start -2.7432 -1.4224)
			(end -2.7432 1.4224)
			(stroke
				(width 0.1524)
				(type default)
			)
			(layer "F.SilkS")
		)
		(fp_line
			(start -2.7432 1.4224)
			(end -2.6416 1.4224)
			(stroke
				(width 0.1524)
				(type default)
			)
			(layer "F.SilkS")
		)
		(fp_line
			(start -2.7432 1.4224)
			(end 2.1336 1.4224)
			(stroke
				(width 0.1524)
				(type default)
			)
			(layer "F.SilkS")
		)
		(fp_line
			(start -2.7178 -0.508)
			(end -2.1844 -0.0508)
			(stroke
				(width 0.1524)
				(type default)
			)
			(layer "F.SilkS")
		)
		(fp_line
			(start -2.6289 3.4417)
			(end -2.6289 1.4732)
			(stroke
				(width 0.381)
				(type default)
			)
			(layer "F.SilkS")
		)
		(fp_line
			(start -2.1844 -0.0508)
			(end -2.7178 0.508)
			(stroke
				(width 0.1524)
				(type default)
			)
			(layer "F.SilkS")
		)
		(fp_line
			(start 2.1336 -1.4224)
			(end -2.7432 -1.4224)
			(stroke
				(width 0.1524)
				(type default)
			)
			(layer "F.SilkS")
		)
		(fp_line
			(start 2.1336 1.4224)
			(end 2.1336 -1.4224)
			(stroke
				(width 0.1524)
				(type default)
			)
			(layer "F.SilkS")
		)
		(fp_poly
			(pts
				(xy -2.2098 -1.4224) (xy -2.2098 1.4224) (xy 2.2098 1.4224) (xy 2.2098 -1.4224)
			)
			(stroke
				(width 0)
				(type default)
			)
			(fill yes)
			(layer "F.SilkS")
		)
		(fp_rect
			(start -2.450084 2.999994)
			(end 2.450084 -2.999994)
			(stroke
				(width 0)
				(type default)
			)
			(fill no)
			(layer "F.CrtYd")
		)
		(fp_poly
			(pts
				(xy -2.8194 3.6322) (xy -2.8194 -3.6322) (xy 2.8194 -3.6322) (xy 2.8194 1.18364) (xy 2.450084 1.18364)
				(xy 2.450084 -2.999994) (xy -2.450084 -2.999994) (xy -2.450084 2.999994) (xy 2.450084 2.999994)
				(xy 2.450084 1.18618) (xy 2.8194 1.18618) (xy 2.8194 3.6322)
			)
			(stroke
				(width 0)
				(type default)
			)
			(fill no)
			(layer "F.CrtYd")
		)
		(fp_rect
			(start -2.8194 3.6322)
			(end 2.8194 -3.6322)
			(stroke
				(width 0)
				(type default)
			)
			(fill no)
			(layer "F.Fab")
		)
		(pad "1" smd rect
			(at -1.905 2.54)
			(size 0.635 1.651)
			(layers "F.Cu" "F.Mask" "F.Paste")
			(net "P12V_A")
		)
		(pad "2" smd rect
			(at -0.635 2.54)
			(size 0.635 1.651)
			(layers "F.Cu" "F.Mask" "F.Paste")
			(net "P12V_A")
		)
		(pad "3" smd rect
			(at 0.635 2.54)
			(size 0.635 1.651)
			(layers "F.Cu" "F.Mask" "F.Paste")
			(net "P12V_A")
		)
		(pad "4" smd rect
			(at 1.905 2.54)
			(size 0.635 1.651)
			(layers "F.Cu" "F.Mask" "F.Paste")
			(net "SW_HDD_N26")
		)
		(pad "5" smd rect
			(at 1.905 -2.54)
			(size 0.635 1.651)
			(layers "F.Cu" "F.Mask" "F.Paste")
			(net "P12V_HDD26")
		)
		(pad "6" smd rect
			(at 0.635 -2.54)
			(size 0.635 1.651)
			(layers "F.Cu" "F.Mask" "F.Paste")
			(net "P12V_HDD26")
		)
		(pad "7" smd rect
			(at -0.635 -2.54)
			(size 0.635 1.651)
			(layers "F.Cu" "F.Mask" "F.Paste")
			(net "P12V_HDD26")
		)
		(pad "8" smd rect
			(at -1.905 -2.54)
			(size 0.635 1.651)
			(layers "F.Cu" "F.Mask" "F.Paste")
			(net "P12V_HDD26")
		)
	)
	(footprint ""
		(layer "F.Cu")
		(at 452.635112 -248.59869 -90)
		(property "Reference" "C640"
			(at 0 0 270)
			(layer "F.SilkS")
			(hide yes)
			(effects
				(font
					(size 1.27 1.27)
				)
			)
		)
		(property "Value" "SC2200P50V2KX-2GP"
			(at 1.1811 -2.7051 270)
			(unlocked yes)
			(layer "F.Fab")
			(hide yes)
			(effects
				(font
					(size 1.016 1.016)
					(thickness 0.1524)
				)
			)
		)
		(property "Device Type" "C402H22"
			(at 1.1811 -4.2291 270)
			(unlocked yes)
			(layer "F.Fab")
			(hide yes)
			(effects
				(font
					(size 1.016 1.016)
					(thickness 0.1524)
				)
			)
		)
		(duplicate_pad_numbers_are_jumpers no)
		(fp_rect
			(start -0.4318 0.9525)
			(end 0.4318 -0.9525)
			(stroke
				(width 0)
				(type default)
			)
			(fill no)
			(layer "F.CrtYd")
		)
		(fp_rect
			(start -0.4318 0.9525)
			(end 0.4318 -0.9525)
			(stroke
				(width 0)
				(type default)
			)
			(fill no)
			(layer "F.Fab")
		)
		(pad "1" smd custom
			(at 0 -0.4445 270)
			(size 0.1524 0.1524)
			(layers "F.Cu" "F.Mask" "F.Paste")
			(net "P5V_C_LL")
			(options
				(clearance outline)
				(anchor circle)
			)
			(primitives
				(gr_poly
					(pts
						(arc
							(start 0.3048 -0.2032)
							(mid 0.275042 -0.275042)
							(end 0.2032 -0.3048)
						)
						(arc
							(start -0.2032 -0.3048)
							(mid -0.275042 -0.275042)
							(end -0.3048 -0.2032)
						)
						(arc
							(start -0.3048 0.2032)
							(mid -0.275042 0.275042)
							(end -0.2032 0.3048)
						)
						(arc
							(start 0.2032 0.3048)
							(mid 0.275042 0.275042)
							(end 0.3048 0.2032)
						)
					)
					(width 0)
					(fill yes)
				)
			)
		)
		(pad "2" smd custom
			(at 0 0.4445 270)
			(size 0.1524 0.1524)
			(layers "F.Cu" "F.Mask" "F.Paste")
			(net "P5V_C_SNB")
			(options
				(clearance outline)
				(anchor circle)
			)
			(primitives
				(gr_poly
					(pts
						(arc
							(start 0.3048 -0.2032)
							(mid 0.275042 -0.275042)
							(end 0.2032 -0.3048)
						)
						(arc
							(start -0.2032 -0.3048)
							(mid -0.275042 -0.275042)
							(end -0.3048 -0.2032)
						)
						(arc
							(start -0.3048 0.2032)
							(mid -0.275042 0.275042)
							(end -0.2032 0.3048)
						)
						(arc
							(start 0.2032 0.3048)
							(mid 0.275042 0.275042)
							(end 0.3048 0.2032)
						)
					)
					(width 0)
					(fill yes)
				)
			)
		)
	)
	(footprint ""
		(layer "F.Cu")
		(at 363.655102 -45.252894 -90)
		(property "Reference" "Q187"
			(at 0 0 270)
			(layer "F.SilkS")
			(hide yes)
			(effects
				(font
					(size 1.27 1.27)
				)
			)
		)
		(property "Value" "2N7002KDW-GP"
			(at -2.3622 -8.2042 270)
			(unlocked yes)
			(layer "F.Fab")
			(hide yes)
			(effects
				(font
					(size 1.016 1.016)
					(thickness 0.1524)
				)
			)
		)
		(property "Device Type" "SOT-363H44"
			(at -2.3622 -10.1092 270)
			(unlocked yes)
			(layer "F.Fab")
			(hide yes)
			(effects
				(font
					(size 1.016 1.016)
					(thickness 0.1524)
				)
			)
		)
		(duplicate_pad_numbers_are_jumpers no)
		(fp_line
			(start -1.4478 1.7018)
			(end 1.4478 1.7018)
			(stroke
				(width 0.1524)
				(type default)
			)
			(layer "F.SilkS")
		)
		(fp_line
			(start 1.4478 1.7018)
			(end 1.4478 -1.7018)
			(stroke
				(width 0.1524)
				(type default)
			)
			(layer "F.SilkS")
		)
		(fp_line
			(start -1.27 1.524)
			(end -1.27 0.6604)
			(stroke
				(width 0.4826)
				(type default)
			)
			(layer "F.SilkS")
		)
		(fp_line
			(start -1.4478 -1.7018)
			(end -1.4478 1.7018)
			(stroke
				(width 0.1524)
				(type default)
			)
			(layer "F.SilkS")
		)
		(fp_line
			(start 1.4478 -1.7018)
			(end -1.4478 -1.7018)
			(stroke
				(width 0.1524)
				(type default)
			)
			(layer "F.SilkS")
		)
		(fp_poly
			(pts
				(xy -1.524 -1.778) (xy 1.524 -1.778) (xy 1.524 1.778) (xy -1.524 1.778)
			)
			(stroke
				(width 0)
				(type default)
			)
			(fill no)
			(layer "F.CrtYd")
		)
		(fp_poly
			(pts
				(xy -1.524 -1.778) (xy 1.524 -1.778) (xy 1.524 1.778) (xy -1.524 1.778)
			)
			(stroke
				(width 0)
				(type default)
			)
			(fill no)
			(layer "F.Fab")
		)
		(pad "1" smd rect
			(at -0.65024 0.9398 270)
			(size 0.4064 1.016)
			(layers "F.Cu" "F.Mask" "F.Paste")
			(net "GND")
		)
		(pad "2" smd rect
			(at 0 0.9398 270)
			(size 0.4064 1.016)
			(layers "F.Cu" "F.Mask" "F.Paste")
			(net "SW_PWR_R_HDD31")
		)
		(pad "3" smd rect
			(at 0.65024 0.9398 270)
			(size 0.4064 1.016)
			(layers "F.Cu" "F.Mask" "F.Paste")
			(net "SW_HDD_P31")
		)
		(pad "4" smd rect
			(at 0.65024 -0.9398 270)
			(size 0.4064 1.016)
			(layers "F.Cu" "F.Mask" "F.Paste")
			(net "GND")
		)
		(pad "5" smd rect
			(at 0 -0.9398 270)
			(size 0.4064 1.016)
			(layers "F.Cu" "F.Mask" "F.Paste")
			(net "SW_HDD_G31")
		)
		(pad "6" smd rect
			(at -0.65024 -0.9398 270)
			(size 0.4064 1.016)
			(layers "F.Cu" "F.Mask" "F.Paste")
			(net "SW_HDD_R31")
		)
	)
	(footprint ""
		(layer "F.Cu")
		(at 237.962694 -244.146578)
		(property "Reference" "R76"
			(at 0 0 0)
			(layer "F.SilkS")
			(hide yes)
			(effects
				(font
					(size 1.27 1.27)
				)
			)
		)
		(property "Value" "4K7R2F-GP"
			(at 0.064008 -3.993896 0)
			(unlocked yes)
			(layer "F.Fab")
			(hide yes)
			(effects
				(font
					(size 1.016 1.016)
					(thickness 0.1524)
				)
			)
		)
		(property "Device Type" "R402H16"
			(at 0.064008 -5.517896 0)
			(unlocked yes)
			(layer "F.Fab")
			(hide yes)
			(effects
				(font
					(size 1.016 1.016)
					(thickness 0.1524)
				)
			)
		)
		(duplicate_pad_numbers_are_jumpers no)
		(fp_line
			(start -0.508 -0.9398)
			(end -0.508 0.9398)
			(stroke
				(width 0.1524)
				(type default)
			)
			(layer "F.SilkS")
		)
		(fp_line
			(start 0.508 -0.9398)
			(end -0.508 -0.9398)
			(stroke
				(width 0.1524)
				(type default)
			)
			(layer "F.SilkS")
		)
		(fp_rect
			(start -0.508 0.9398)
			(end 0.508 -0.9398)
			(stroke
				(width 0)
				(type default)
			)
			(fill no)
			(layer "F.CrtYd")
		)
		(fp_rect
			(start -0.508 0.9398)
			(end 0.508 -0.9398)
			(stroke
				(width 0)
				(type default)
			)
			(fill no)
			(layer "F.Fab")
		)
		(pad "1" smd custom
			(at 0 -0.4445)
			(size 0.1397 0.1397)
			(layers "F.Cu" "F.Mask" "F.Paste")
			(net "P3V3_STBY_A")
			(options
				(clearance outline)
				(anchor circle)
			)
			(primitives
				(gr_poly
					(pts
						(arc
							(start -0.1778 -0.2794)
							(mid -0.249642 -0.249642)
							(end -0.2794 -0.1778)
						)
						(arc
							(start -0.2794 0.1778)
							(mid -0.249642 0.249642)
							(end -0.1778 0.2794)
						)
						(arc
							(start 0.1778 0.2794)
							(mid 0.249642 0.249642)
							(end 0.2794 0.1778)
						)
						(arc
							(start 0.2794 -0.1778)
							(mid 0.249642 -0.249642)
							(end 0.1778 -0.2794)
						)
					)
					(width 0)
					(fill yes)
				)
			)
		)
		(pad "2" smd custom
			(at 0 0.4445)
			(size 0.1397 0.1397)
			(layers "F.Cu" "F.Mask" "F.Paste")
			(net "IO_EXP1_INT_N")
			(options
				(clearance outline)
				(anchor circle)
			)
			(primitives
				(gr_poly
					(pts
						(arc
							(start -0.1778 -0.2794)
							(mid -0.249642 -0.249642)
							(end -0.2794 -0.1778)
						)
						(arc
							(start -0.2794 0.1778)
							(mid -0.249642 0.249642)
							(end -0.1778 0.2794)
						)
						(arc
							(start 0.1778 0.2794)
							(mid 0.249642 0.249642)
							(end 0.2794 0.1778)
						)
						(arc
							(start 0.2794 -0.1778)
							(mid 0.249642 -0.249642)
							(end 0.1778 -0.2794)
						)
					)
					(width 0)
					(fill yes)
				)
			)
		)
	)
	(footprint ""
		(layer "F.Cu")
		(at 350.1136 -298.704)
		(property "Reference" "TP37"
			(at 0 0 0)
			(layer "F.SilkS")
			(hide yes)
			(effects
				(font
					(size 1.27 1.27)
				)
			)
		)
		(property "Value" "TPAD32-GP"
			(at -0.0508 -1.6764 0)
			(unlocked yes)
			(layer "F.Fab")
			(hide yes)
			(effects
				(font
					(size 1.016 1.016)
					(thickness 0.1524)
				)
			)
		)
		(property "Device Type" "TPAD32"
			(at -0.0508 -3.2004 0)
			(unlocked yes)
			(layer "F.Fab")
			(hide yes)
			(effects
				(font
					(size 1.016 1.016)
					(thickness 0.1524)
				)
			)
		)
		(duplicate_pad_numbers_are_jumpers no)
		(fp_poly
			(pts
				(arc
					(start 0.4064 0)
					(mid -0.4064 0)
					(end 0.4064 0)
				)
			)
			(stroke
				(width 0)
				(type default)
			)
			(fill no)
			(layer "F.CrtYd")
		)
		(fp_poly
			(pts
				(arc
					(start 0.7112 0)
					(mid -0.7112 0)
					(end 0.7112 0)
				)
			)
			(stroke
				(width 0)
				(type default)
			)
			(fill no)
			(layer "F.Fab")
		)
		(pad "1" smd circle
			(at 0 0)
			(size 0.8128 0.8128)
			(layers "F.Cu" "F.Mask" "F.Paste")
			(net "ACT_HDD_7")
		)
	)
	(footprint ""
		(layer "F.Cu")
		(at 55.486046 -301.287942)
		(property "Reference" "C58"
			(at 0 0 0)
			(layer "F.SilkS")
			(hide yes)
			(effects
				(font
					(size 1.27 1.27)
				)
			)
		)
		(property "Value" "SC4D7U25V5KX-1-GP"
			(at -0.0762 -6.1214 0)
			(unlocked yes)
			(layer "F.Fab")
			(hide yes)
			(effects
				(font
					(size 1.016 1.016)
					(thickness 0.1524)
				)
			)
		)
		(property "Device Type" "C805H58"
			(at -0.0762 -8.1534 0)
			(unlocked yes)
			(layer "F.Fab")
			(hide yes)
			(effects
				(font
					(size 1.016 1.016)
					(thickness 0.1524)
				)
			)
		)
		(duplicate_pad_numbers_are_jumpers no)
		(fp_line
			(start 0.635 0)
			(end -0.635 0)
			(stroke
				(width 0.508)
				(type default)
			)
			(layer "F.SilkS")
		)
		(fp_rect
			(start -0.9652 1.778)
			(end 0.9652 -1.778)
			(stroke
				(width 0)
				(type default)
			)
			(fill no)
			(layer "F.CrtYd")
		)
		(fp_poly
			(pts
				(xy -0.9652 -1.778) (xy 0.9652 -1.778) (xy 0.9652 1.778) (xy -0.9652 1.778)
			)
			(stroke
				(width 0)
				(type default)
			)
			(fill no)
			(layer "F.Fab")
		)
		(pad "1" smd rect
			(at 0 -0.9652)
			(size 1.397 1.143)
			(layers "F.Cu" "F.Mask" "F.Paste")
			(net "P12V_HDD1")
		)
		(pad "2" smd rect
			(at 0 0.9652)
			(size 1.397 1.143)
			(layers "F.Cu" "F.Mask" "F.Paste")
			(net "GND")
		)
	)
)
